(kicad_pcb
	(version 20260206)
	(generator "pcbnew")
	(generator_version "10.0")
	(general
		(thickness 1.6)
		(legacy_teardrops no)
	)
	(paper "A4")
	(title_block
		(title "01162023_DA0F0TEBIF0_F0T_Expander_BD_F_brd_V02_OCP.brd")
		(comment 1 "Grand Teton / footprints 5130-5133 of 9728")
	)
	(layers
		(0 "F.Cu" signal "TOP")
		(4 "In1.Cu" signal "GND")
		(6 "In2.Cu" signal "VCC")
		(8 "In3.Cu" signal "VCC1")
		(10 "In4.Cu" signal "GND1")
		(12 "In5.Cu" signal "IN1")
		(14 "In6.Cu" signal "GND2")
		(16 "In7.Cu" signal "IN2")
		(18 "In8.Cu" signal "GND3")
		(20 "In9.Cu" signal "IN3")
		(22 "In10.Cu" signal "GND4")
		(24 "In11.Cu" signal "IN4")
		(26 "In12.Cu" signal "GND5")
		(28 "In13.Cu" signal "IN5")
		(30 "In14.Cu" signal "GND6")
		(32 "In15.Cu" signal "IN6")
		(34 "In16.Cu" signal "GND7")
		(2 "B.Cu" signal "BOTTOM")
		(9 "F.Adhes" user "F.Adhesive")
		(11 "B.Adhes" user "B.Adhesive")
		(13 "F.Paste" user "Package Geometry/Pastemask Top")
		(15 "B.Paste" user "Package Geometry/Pastemask Bottom")
		(5 "F.SilkS" user "Ref Des/Silkscreen Top")
		(7 "B.SilkS" user "Ref Des/Silkscreen Bottom")
		(1 "F.Mask" user "Board Geometry/Soldermask Top")
		(3 "B.Mask" user "Board Geometry/Soldermask Bottom")
		(17 "Dwgs.User" user "User.Drawings")
		(19 "Cmts.User" user "User.Comments")
		(21 "Eco1.User" user "User.Eco1")
		(23 "Eco2.User" user "User.Eco2")
		(25 "Edge.Cuts" user "Board Geometry/Outline")
		(27 "Margin" user)
		(31 "F.CrtYd" user "Package Geometry/Place Bound Top")
		(29 "B.CrtYd" user "Package Geometry/Place Bound Bottom")
		(35 "F.Fab" user "Ref Des/Assembly Top")
		(33 "B.Fab" user "Ref Des/Assembly Bottom")
	)
	(footprint ""
		(layer "F.Cu")
		(at 346.075 -157.988)
		(property "Reference" "U349"
			(at -1.4478 -4.613148 0)
			(unlocked yes)
			(layer "F.SilkS")
			(effects
				(font
					(size 0.7874 0.5842)
					(thickness 0.1524)
				)
				(justify left)
			)
		)
		(property "Value" ""
			(at 0 0 0)
			(layer "F.Fab")
			(effects
				(font
					(size 1.27 1.27)
				)
			)
		)
		(duplicate_pad_numbers_are_jumpers no)
		(fp_line
			(start -2.097532 -3.949954)
			(end -2.097532 3.949954)
			(stroke
				(width 0.1524)
				(type default)
			)
			(layer "F.SilkS")
		)
		(fp_line
			(start -2.097532 3.949954)
			(end 2.097532 3.949954)
			(stroke
				(width 0.1524)
				(type default)
			)
			(layer "F.SilkS")
		)
		(fp_line
			(start -1.409954 -3.949954)
			(end -2.097532 -3.949954)
			(stroke
				(width 0.1524)
				(type default)
			)
			(layer "F.SilkS")
		)
		(fp_line
			(start 0 -2.54)
			(end -1.409954 -3.949954)
			(stroke
				(width 0.1524)
				(type default)
			)
			(layer "F.SilkS")
		)
		(fp_line
			(start 1.409954 -3.949954)
			(end 0 -2.54)
			(stroke
				(width 0.1524)
				(type default)
			)
			(layer "F.SilkS")
		)
		(fp_line
			(start 2.097532 -3.949954)
			(end 1.409954 -3.949954)
			(stroke
				(width 0.1524)
				(type default)
			)
			(layer "F.SilkS")
		)
		(fp_line
			(start 2.097532 3.949954)
			(end 2.097532 -3.949954)
			(stroke
				(width 0.1524)
				(type default)
			)
			(layer "F.SilkS")
		)
		(fp_poly
			(pts
				(xy -4.7498 -4.182872) (xy -4.7498 -3.166872) (xy -3.7338 -3.674872)
			)
			(stroke
				(width 0)
				(type default)
			)
			(fill yes)
			(layer "F.SilkS")
		)
		(fp_line
			(start -2.249932 -3.949954)
			(end -2.249932 3.949954)
			(stroke
				(width 0.1)
				(type default)
			)
			(layer "F.Fab")
		)
		(fp_line
			(start -2.249932 3.949954)
			(end 2.249932 3.949954)
			(stroke
				(width 0.1)
				(type default)
			)
			(layer "F.Fab")
		)
		(fp_line
			(start 2.249932 -3.949954)
			(end -2.249932 -3.949954)
			(stroke
				(width 0.1)
				(type default)
			)
			(layer "F.Fab")
		)
		(fp_line
			(start 2.249932 3.949954)
			(end 2.249932 -3.949954)
			(stroke
				(width 0.1)
				(type default)
			)
			(layer "F.Fab")
		)
		(fp_poly
			(pts
				(xy -4.7498 -4.182872) (xy -4.7498 -3.166872) (xy -3.7338 -3.674872)
			)
			(stroke
				(width 0)
				(type default)
			)
			(fill yes)
			(layer "F.Fab")
		)
		(pad "1" smd rect
			(at -2.925064 -3.674872 270)
			(size 0.6096 1.3716)
			(layers "F.Cu" "F.Mask" "F.Paste")
			(net "PEX3_PCA9555_0_INT_N")
		)
		(pad "2" smd rect
			(at -2.925064 -2.925064 270)
			(size 0.4064 1.3716)
			(layers "F.Cu" "F.Mask" "F.Paste")
			(net "PCA9555_0_PEX3_A1")
		)
		(pad "3" smd rect
			(at -2.925064 -2.275078 270)
			(size 0.4064 1.3716)
			(layers "F.Cu" "F.Mask" "F.Paste")
			(net "PCA9555_0_PEX3_A2")
		)
		(pad "4" smd rect
			(at -2.925064 -1.625092 270)
			(size 0.4064 1.3716)
			(layers "F.Cu" "F.Mask" "F.Paste")
			(net "PRSNT_SSD12_FPGA_PCA9555_N")
		)
		(pad "5" smd rect
			(at -2.925064 -0.975106 270)
			(size 0.4064 1.3716)
			(layers "F.Cu" "F.Mask" "F.Paste")
			(net "SSD12_PEX_PWR_EN")
		)
		(pad "6" smd rect
			(at -2.925064 -0.32512 270)
			(size 0.4064 1.3716)
			(layers "F.Cu" "F.Mask" "F.Paste")
			(net "RST_PEX_SSD12_PERST_N")
		)
		(pad "7" smd rect
			(at -2.925064 0.32512 270)
			(size 0.4064 1.3716)
			(layers "F.Cu" "F.Mask" "F.Paste")
			(net "Net_1185")
		)
		(pad "8" smd rect
			(at -2.925064 0.975106 270)
			(size 0.4064 1.3716)
			(layers "F.Cu" "F.Mask" "F.Paste")
			(net "PRSNT_SSD13_FPGA_PCA9555_N")
		)
		(pad "9" smd rect
			(at -2.925064 1.625092 270)
			(size 0.4064 1.3716)
			(layers "F.Cu" "F.Mask" "F.Paste")
			(net "SSD13_PEX_PWR_EN")
		)
		(pad "10" smd rect
			(at -2.925064 2.275078 270)
			(size 0.4064 1.3716)
			(layers "F.Cu" "F.Mask" "F.Paste")
			(net "RST_PEX_SSD13_PERST_N")
		)
		(pad "11" smd rect
			(at -2.925064 2.925064 270)
			(size 0.4064 1.3716)
			(layers "F.Cu" "F.Mask" "F.Paste")
			(net "Net_1183")
		)
		(pad "12" smd rect
			(at -2.925064 3.674872 270)
			(size 0.6096 1.3716)
			(layers "F.Cu" "F.Mask" "F.Paste")
			(net "GND")
		)
		(pad "13" smd rect
			(at 2.925064 3.674872 270)
			(size 0.6096 1.3716)
			(layers "F.Cu" "F.Mask" "F.Paste")
			(net "PRSNT_NIC6_FPGA_PCA9555_N")
		)
		(pad "14" smd rect
			(at 2.925064 2.925064 270)
			(size 0.4064 1.3716)
			(layers "F.Cu" "F.Mask" "F.Paste")
			(net "NIC6_PEX_PWR_EN")
		)
		(pad "15" smd rect
			(at 2.925064 2.275078 270)
			(size 0.4064 1.3716)
			(layers "F.Cu" "F.Mask" "F.Paste")
			(net "RST_PEX_NIC6_PERST_N")
		)
		(pad "16" smd rect
			(at 2.925064 1.625092 270)
			(size 0.4064 1.3716)
			(layers "F.Cu" "F.Mask" "F.Paste")
			(net "Net_1182")
		)
		(pad "17" smd rect
			(at 2.925064 0.975106 270)
			(size 0.4064 1.3716)
			(layers "F.Cu" "F.Mask" "F.Paste")
			(net "Net_8968")
		)
		(pad "18" smd rect
			(at 2.925064 0.32512 270)
			(size 0.4064 1.3716)
			(layers "F.Cu" "F.Mask" "F.Paste")
			(net "Net_8967")
		)
		(pad "19" smd rect
			(at 2.925064 -0.32512 270)
			(size 0.4064 1.3716)
			(layers "F.Cu" "F.Mask" "F.Paste")
			(net "Net_8966")
		)
		(pad "20" smd rect
			(at 2.925064 -0.975106 270)
			(size 0.4064 1.3716)
			(layers "F.Cu" "F.Mask" "F.Paste")
			(net "Net_8965")
		)
		(pad "21" smd rect
			(at 2.925064 -1.625092 270)
			(size 0.4064 1.3716)
			(layers "F.Cu" "F.Mask" "F.Paste")
			(net "PCA9555_0_PEX3_A0")
		)
		(pad "22" smd rect
			(at 2.925064 -2.275078 270)
			(size 0.4064 1.3716)
			(layers "F.Cu" "F.Mask" "F.Paste")
			(net "SMB_PEX3_PCA9555_SCL")
		)
		(pad "23" smd rect
			(at 2.925064 -2.925064 270)
			(size 0.4064 1.3716)
			(layers "F.Cu" "F.Mask" "F.Paste")
			(net "SMB_PEX3_PCA9555_SDA")
		)
		(pad "24" smd rect
			(at 2.925064 -3.674872 270)
			(size 0.6096 1.3716)
			(layers "F.Cu" "F.Mask" "F.Paste")
			(net "P3V3_AUX")
		)
	)
	(footprint ""
		(layer "F.Cu")
		(at 230.529892 -79.005684 -90)
		(property "Reference" "U110"
			(at 2.8575 1.565656 0)
			(unlocked yes)
			(layer "F.SilkS")
			(effects
				(font
					(size 0.7874 0.5842)
					(thickness 0.1524)
				)
				(justify left)
			)
		)
		(property "Value" ""
			(at 0 0 270)
			(layer "F.Fab")
			(effects
				(font
					(size 1.27 1.27)
				)
			)
		)
		(duplicate_pad_numbers_are_jumpers no)
		(fp_line
			(start -0.674878 0.824992)
			(end -0.674878 0.403098)
			(stroke
				(width 0.1524)
				(type default)
			)
			(layer "F.SilkS")
		)
		(fp_line
			(start -0.61595 0.824992)
			(end -0.674878 0.824992)
			(stroke
				(width 0.1524)
				(type default)
			)
			(layer "F.SilkS")
		)
		(fp_line
			(start 0.674878 0.824992)
			(end 0.61595 0.824992)
			(stroke
				(width 0.1524)
				(type default)
			)
			(layer "F.SilkS")
		)
		(fp_line
			(start 0.674878 0.403098)
			(end 0.674878 0.824992)
			(stroke
				(width 0.1524)
				(type default)
			)
			(layer "F.SilkS")
		)
		(fp_line
			(start -0.674878 -0.403098)
			(end -0.674878 -0.824992)
			(stroke
				(width 0.1524)
				(type default)
			)
			(layer "F.SilkS")
		)
		(fp_line
			(start -0.674878 -0.824992)
			(end -0.61595 -0.824992)
			(stroke
				(width 0.1524)
				(type default)
			)
			(layer "F.SilkS")
		)
		(fp_line
			(start 0.61595 -0.824992)
			(end 0.674878 -0.824992)
			(stroke
				(width 0.1524)
				(type default)
			)
			(layer "F.SilkS")
		)
		(fp_line
			(start 0.674878 -0.824992)
			(end 0.674878 -0.403098)
			(stroke
				(width 0.1524)
				(type default)
			)
			(layer "F.SilkS")
		)
		(fp_poly
			(pts
				(xy -1.067308 -0.790702) (xy -1.354836 -0.503428) (xy -0.923798 -0.359664)
			)
			(stroke
				(width 0)
				(type default)
			)
			(fill yes)
			(layer "F.SilkS")
		)
		(fp_line
			(start -0.674878 0.824992)
			(end -0.674878 -0.824992)
			(stroke
				(width 0.1)
				(type default)
			)
			(layer "F.Fab")
		)
		(fp_line
			(start 0.674878 0.824992)
			(end -0.674878 0.824992)
			(stroke
				(width 0.1)
				(type default)
			)
			(layer "F.Fab")
		)
		(fp_line
			(start -0.674878 -0.824992)
			(end 0.674878 -0.824992)
			(stroke
				(width 0.1)
				(type default)
			)
			(layer "F.Fab")
		)
		(fp_line
			(start 0.674878 -0.824992)
			(end 0.674878 0.824992)
			(stroke
				(width 0.1)
				(type default)
			)
			(layer "F.Fab")
		)
		(fp_poly
			(pts
				(xy -1.344422 -0.403098) (xy -1.344422 0.003302) (xy -0.938022 -0.199898)
			)
			(stroke
				(width 0)
				(type default)
			)
			(fill yes)
			(layer "F.Fab")
		)
		(fp_text user "3"
			(at -1.12903 1.313688 0)
			(unlocked yes)
			(layer "F.SilkS")
			(effects
				(font
					(size 0.635 0.4064)
					(thickness 0.1524)
				)
				(justify left)
			)
		)
		(fp_text user "5"
			(at 1.437132 1.313688 0)
			(unlocked yes)
			(layer "F.SilkS")
			(effects
				(font
					(size 0.635 0.4064)
					(thickness 0.1524)
				)
				(justify left)
			)
		)
		(fp_text user "10"
			(at -1.247394 -0.408686 0)
			(unlocked yes)
			(layer "F.SilkS")
			(effects
				(font
					(size 0.635 0.4064)
					(thickness 0.1524)
				)
				(justify left)
			)
		)
		(fp_text user "8"
			(at 1.300734 -0.897382 0)
			(unlocked yes)
			(layer "F.SilkS")
			(effects
				(font
					(size 0.635 0.4064)
					(thickness 0.1524)
				)
				(justify left)
			)
		)
		(fp_text user "3"
			(at -1.210056 0.999744 270)
			(unlocked yes)
			(layer "F.Fab")
			(effects
				(font
					(size 0.635 0.4064)
					(thickness 0.1524)
				)
				(justify left)
			)
		)
		(fp_text user "5"
			(at 0.777748 0.940054 270)
			(unlocked yes)
			(layer "F.Fab")
			(effects
				(font
					(size 0.635 0.4064)
					(thickness 0.1524)
				)
				(justify left)
			)
		)
		(fp_text user "10"
			(at -1.505458 -1.33858 270)
			(unlocked yes)
			(layer "F.Fab")
			(effects
				(font
					(size 0.635 0.4064)
					(thickness 0.1524)
				)
				(justify left)
			)
		)
		(fp_text user "8"
			(at 0.582676 -1.368552 270)
			(unlocked yes)
			(layer "F.Fab")
			(effects
				(font
					(size 0.635 0.4064)
					(thickness 0.1524)
				)
				(justify left)
			)
		)
		(pad "1" smd rect
			(at -0.459994 -0.199898)
			(size 0.1524 0.7112)
			(layers "F.Cu" "F.Mask" "F.Paste")
			(net "USB2_PEX_HUB_DP")
		)
		(pad "2" smd rect
			(at -0.459994 0.199898)
			(size 0.1524 0.7112)
			(layers "F.Cu" "F.Mask" "F.Paste")
			(net "USB2_PEX_HUB_DN")
		)
		(pad "3" smd rect
			(at -0.40005 0.735076 270)
			(size 0.1778 0.508)
			(layers "F.Cu" "F.Mask" "F.Paste")
			(net "GND")
		)
		(pad "4" smd rect
			(at 0 0.735076 270)
			(size 0.1778 0.508)
			(layers "F.Cu" "F.Mask" "F.Paste")
			(net "USB2_MICRO_DN")
		)
		(pad "5" smd rect
			(at 0.40005 0.735076 270)
			(size 0.1778 0.508)
			(layers "F.Cu" "F.Mask" "F.Paste")
			(net "USB2_MICRO_DP")
		)
		(pad "6" smd rect
			(at 0.459994 0.199898)
			(size 0.1524 0.7112)
			(layers "F.Cu" "F.Mask" "F.Paste")
			(net "USB2_FIO_DN")
		)
		(pad "7" smd rect
			(at 0.459994 -0.199898)
			(size 0.1524 0.7112)
			(layers "F.Cu" "F.Mask" "F.Paste")
			(net "USB2_FIO_DP")
		)
		(pad "8" smd rect
			(at 0.40005 -0.735076 270)
			(size 0.1778 0.508)
			(layers "F.Cu" "F.Mask" "F.Paste")
			(net "PWRGD_P3V3_AUX_MUX_R_N")
		)
		(pad "9" smd rect
			(at 0 -0.735076 270)
			(size 0.1778 0.508)
			(layers "F.Cu" "F.Mask" "F.Paste")
			(net "P3V3_AUX")
		)
		(pad "10" smd rect
			(at -0.40005 -0.735076 270)
			(size 0.1778 0.508)
			(layers "F.Cu" "F.Mask" "F.Paste")
			(net "PEX_USB2_SEL")
		)
	)
	(footprint ""
		(layer "F.Cu")
		(at 100.216462 -100.178108 90)
		(property "Reference" "PC306"
			(at 0 0 90)
			(layer "F.SilkS")
			(hide yes)
			(effects
				(font
					(size 1.27 1.27)
				)
			)
		)
		(property "Value" ""
			(at 0 0 90)
			(layer "F.Fab")
			(effects
				(font
					(size 1.27 1.27)
				)
			)
		)
		(duplicate_pad_numbers_are_jumpers no)
		(fp_line
			(start 0.7874 -0.4064)
			(end 0.7874 0.4064)
			(stroke
				(width 0.1524)
				(type default)
			)
			(layer "F.SilkS")
		)
		(fp_line
			(start -0.7874 -0.4064)
			(end 0.7874 -0.4064)
			(stroke
				(width 0.1524)
				(type default)
			)
			(layer "F.SilkS")
		)
		(fp_line
			(start 0.7874 0.4064)
			(end -0.7874 0.4064)
			(stroke
				(width 0.1524)
				(type default)
			)
			(layer "F.SilkS")
		)
		(fp_line
			(start -0.7874 0.4064)
			(end -0.7874 -0.4064)
			(stroke
				(width 0.1524)
				(type default)
			)
			(layer "F.SilkS")
		)
		(fp_line
			(start -0.12065 -0.305054)
			(end -0.12065 -0.2794)
			(stroke
				(width 0.1)
				(type default)
			)
			(layer "F.Fab")
		)
		(fp_line
			(start -0.67945 -0.305054)
			(end -0.12065 -0.305054)
			(stroke
				(width 0.1)
				(type default)
			)
			(layer "F.Fab")
		)
		(fp_line
			(start 0.67945 -0.3048)
			(end 0.67945 0.3048)
			(stroke
				(width 0.1)
				(type default)
			)
			(layer "F.Fab")
		)
		(fp_line
			(start 0.12065 -0.3048)
			(end 0.67945 -0.3048)
			(stroke
				(width 0.1)
				(type default)
			)
			(layer "F.Fab")
		)
		(fp_line
			(start 0.12065 -0.2794)
			(end 0.12065 -0.3048)
			(stroke
				(width 0.1)
				(type default)
			)
			(layer "F.Fab")
		)
		(fp_line
			(start -0.12065 -0.2794)
			(end 0.12065 -0.2794)
			(stroke
				(width 0.1)
				(type default)
			)
			(layer "F.Fab")
		)
		(fp_line
			(start 0.120396 0.2794)
			(end -0.12065 0.2794)
			(stroke
				(width 0.1)
				(type default)
			)
			(layer "F.Fab")
		)
		(fp_line
			(start -0.12065 0.2794)
			(end -0.12065 0.3048)
			(stroke
				(width 0.1)
				(type default)
			)
			(layer "F.Fab")
		)
		(fp_line
			(start 0.67945 0.3048)
			(end 0.120396 0.3048)
			(stroke
				(width 0.1)
				(type default)
			)
			(layer "F.Fab")
		)
		(fp_line
			(start 0.120396 0.3048)
			(end 0.120396 0.2794)
			(stroke
				(width 0.1)
				(type default)
			)
			(layer "F.Fab")
		)
		(fp_line
			(start -0.12065 0.3048)
			(end -0.67945 0.3048)
			(stroke
				(width 0.1)
				(type default)
			)
			(layer "F.Fab")
		)
		(fp_line
			(start -0.67945 0.3048)
			(end -0.67945 -0.305054)
			(stroke
				(width 0.1)
				(type default)
			)
			(layer "F.Fab")
		)
		(pad "1" smd circle
			(at -0.40005 0 90)
			(size 0 0)
			(layers "F.Cu" "F.Mask" "F.Paste")
			(net "P12V_AUX")
		)
		(pad "2" smd circle
			(at 0.40005 0 90)
			(size 0 0)
			(layers "F.Cu" "F.Mask" "F.Paste")
			(net "GND")
		)
	)
	(footprint ""
		(layer "F.Cu")
		(at 323.115686 -309.760366 135)
		(property "Reference" "R1387"
			(at 0 0 135)
			(layer "F.SilkS")
			(hide yes)
			(effects
				(font
					(size 1.27 1.27)
				)
			)
		)
		(property "Value" ""
			(at 0 0 135)
			(layer "F.Fab")
			(effects
				(font
					(size 1.27 1.27)
				)
			)
		)
		(duplicate_pad_numbers_are_jumpers no)
		(fp_line
			(start 0.787389 -0.406267)
			(end 0.787389 0.406267)
			(stroke
				(width 0.1524)
				(type default)
			)
			(layer "F.SilkS")
		)
		(fp_line
			(start 0.787389 0.406267)
			(end -0.787389 0.406267)
			(stroke
				(width 0.1524)
				(type default)
			)
			(layer "F.SilkS")
		)
		(fp_line
			(start -0.787389 -0.406267)
			(end 0.787389 -0.406267)
			(stroke
				(width 0.1524)
				(type default)
			)
			(layer "F.SilkS")
		)
		(fp_line
			(start -0.787389 0.406267)
			(end -0.787389 -0.406267)
			(stroke
				(width 0.1524)
				(type default)
			)
			(layer "F.SilkS")
		)
		(fp_line
			(start 0.679446 -0.30479)
			(end 0.679446 0.30479)
			(stroke
				(width 0.1)
				(type default)
			)
			(layer "F.Fab")
		)
		(fp_line
			(start 0.120515 -0.30479)
			(end 0.679446 -0.30479)
			(stroke
				(width 0.1)
				(type default)
			)
			(layer "F.Fab")
		)
		(fp_line
			(start 0.120695 -0.279466)
			(end 0.120515 -0.30479)
			(stroke
				(width 0.1)
				(type default)
			)
			(layer "F.Fab")
		)
		(fp_line
			(start 0.679446 0.30479)
			(end 0.120515 0.30479)
			(stroke
				(width 0.1)
				(type default)
			)
			(layer "F.Fab")
		)
		(fp_line
			(start -0.120695 -0.304969)
			(end -0.120695 -0.279466)
			(stroke
				(width 0.1)
				(type default)
			)
			(layer "F.Fab")
		)
		(fp_line
			(start -0.120695 -0.279466)
			(end 0.120695 -0.279466)
			(stroke
				(width 0.1)
				(type default)
			)
			(layer "F.Fab")
		)
		(fp_line
			(start 0.120335 0.279466)
			(end -0.120695 0.279466)
			(stroke
				(width 0.1)
				(type default)
			)
			(layer "F.Fab")
		)
		(fp_line
			(start 0.120515 0.30479)
			(end 0.120335 0.279466)
			(stroke
				(width 0.1)
				(type default)
			)
			(layer "F.Fab")
		)
		(fp_line
			(start -0.679446 -0.305149)
			(end -0.120695 -0.304969)
			(stroke
				(width 0.1)
				(type default)
			)
			(layer "F.Fab")
		)
		(fp_line
			(start -0.120695 0.279466)
			(end -0.120515 0.30479)
			(stroke
				(width 0.1)
				(type default)
			)
			(layer "F.Fab")
		)
		(fp_line
			(start -0.120515 0.30479)
			(end -0.679446 0.30479)
			(stroke
				(width 0.1)
				(type default)
			)
			(layer "F.Fab")
		)
		(fp_line
			(start -0.679446 0.30479)
			(end -0.679446 -0.305149)
			(stroke
				(width 0.1)
				(type default)
			)
			(layer "F.Fab")
		)
		(pad "1" smd circle
			(at -0.40005 0 135)
			(size 0 0)
			(layers "F.Cu" "F.Mask" "F.Paste")
			(net "GND")
		)
		(pad "2" smd circle
			(at 0.40005 0 135)
			(size 0 0)
			(layers "F.Cu" "F.Mask" "F.Paste")
			(net "PEX2_SPARE0")
		)
	)
)
